(kicad_pcb
	(version 20241229)
	(generator "pcbnew")
	(generator_version "9.0")
	(general
		(thickness 1.62)
		(legacy_teardrops no)
	)
	(paper "A3")
	(title_block
		(title "COM Express 7 Baseboard")
		(date "2025-02-04")
		(rev "1.1.2")
		(company "Antmicro Ltd")
		(comment 1 "www.antmicro.com")
		(comment 9 "footprints 277-280 of 802")
	)
	(layers
		(0 "F.Cu" signal)
		(4 "In1.Cu" signal)
		(6 "In2.Cu" signal)
		(8 "In3.Cu" signal)
		(10 "In4.Cu" signal)
		(12 "In5.Cu" signal)
		(14 "In6.Cu" signal)
		(2 "B.Cu" signal)
		(9 "F.Adhes" user "F.Adhesive")
		(11 "B.Adhes" user "B.Adhesive")
		(13 "F.Paste" user)
		(15 "B.Paste" user)
		(5 "F.SilkS" user "F.Silkscreen")
		(7 "B.SilkS" user "B.Silkscreen")
		(1 "F.Mask" user)
		(3 "B.Mask" user)
		(17 "Dwgs.User" user "User.Drawings")
		(19 "Cmts.User" user "User.Comments")
		(21 "Eco1.User" user "User.Eco1")
		(23 "Eco2.User" user "User.Eco2")
		(25 "Edge.Cuts" user)
		(27 "Margin" user)
		(31 "F.CrtYd" user "F.Courtyard")
		(29 "B.CrtYd" user "B.Courtyard")
		(35 "F.Fab" user)
		(33 "B.Fab" user)
	)
	(footprint "antmicro-footprints:Trans_Eth_4.7x3.3mm"
		(layer "F.Cu")
		(at 130.63 112.16)
		(property "Reference" "T5"
			(at 4.97 0.25 0)
			(unlocked yes)
			(layer "F.SilkS")
			(effects
				(font
					(size 0.7 0.7)
					(thickness 0.15)
				)
				(justify left bottom)
			)
		)
		(property "Value" "Trans_SM453229-381N7Y"
			(at 2.39 11.52 0)
			(unlocked yes)
			(layer "F.Fab")
			(effects
				(font
					(size 0.7 0.7)
					(thickness 0.15)
				)
				(justify left bottom)
			)
		)
		(property "Datasheet" "https://eu.mouser.com/datasheet/2/54/bourns_02132019_SM453229-381N7Y_datasheet-1532071.pdf"
			(at 0 0 0)
			(layer "F.Fab")
			(hide yes)
			(effects
				(font
					(size 1.27 1.27)
					(thickness 0.15)
				)
			)
		)
		(property "Author" "Antmicro"
			(at 0 0 0)
			(layer "F.Fab")
			(hide yes)
			(effects
				(font
					(size 1 1)
					(thickness 0.15)
				)
			)
		)
		(property "License" "Apache-2.0"
			(at 0 0 0)
			(layer "F.Fab")
			(hide yes)
			(effects
				(font
					(size 1 1)
					(thickness 0.15)
				)
			)
		)
		(property "MPN" "SM453229-381N7Y"
			(at 0 0 0)
			(layer "F.Fab")
			(hide yes)
			(effects
				(font
					(size 1 1)
					(thickness 0.15)
				)
			)
		)
		(property "Manufacturer" "Bourns"
			(at 0 0 0)
			(layer "F.Fab")
			(hide yes)
			(effects
				(font
					(size 1 1)
					(thickness 0.15)
				)
			)
		)
		(sheetname "2xUSB3.0+RJ45")
		(sheetfile "usb3+rj45.kicad_sch")
		(attr smd)
		(fp_line
			(start -0.15 -0.6)
			(end -0.15 0.55)
			(stroke
				(width 0.1)
				(type default)
			)
			(layer "F.SilkS")
		)
		(fp_line
			(start 3.4 -1.6)
			(end 1 -1.6)
			(stroke
				(width 0.1)
				(type default)
			)
			(layer "F.SilkS")
		)
		(fp_line
			(start 3.4 1.7)
			(end 1 1.7)
			(stroke
				(width 0.1)
				(type default)
			)
			(layer "F.SilkS")
		)
		(fp_line
			(start 4.55 -0.25)
			(end 4.55 0.9)
			(stroke
				(width 0.1)
				(type default)
			)
			(layer "F.SilkS")
		)
		(fp_circle
			(center 0.1 2.3)
			(end 0.15 2.3)
			(stroke
				(width 0.15)
				(type solid)
			)
			(fill yes)
			(layer "F.SilkS")
		)
		(fp_rect
			(start -0.6 -1.9)
			(end 4.94 1.9)
			(stroke
				(width 0.05)
				(type solid)
			)
			(fill no)
			(layer "F.CrtYd")
		)
		(pad "1" smd roundrect
			(at 0.17 1.5)
			(size 0.96 0.27)
			(layers "F.Cu" "F.Mask" "F.Paste")
			(roundrect_rratio 0.25)
			(net 689 "/2xUSB3.0+RJ45/DA_FL+")
			(pinfunction "1")
			(pintype "passive")
			(teardrops
				(best_length_ratio 0.2)
				(max_length 1)
				(best_width_ratio 0.9)
				(max_width 2)
				(curved_edges yes)
				(filter_ratio 0.9)
				(enabled yes)
				(allow_two_segments yes)
				(prefer_zone_connections yes)
			)
		)
		(pad "2" smd roundrect
			(at 0.115 0.855)
			(size 0.85 0.28)
			(layers "F.Cu" "F.Mask" "F.Paste")
			(roundrect_rratio 0.25)
			(net 690 "/2xUSB3.0+RJ45/DA_FL-")
			(pinfunction "2")
			(pintype "passive")
			(teardrops
				(best_length_ratio 0.2)
				(max_length 1)
				(best_width_ratio 0.9)
				(max_width 2)
				(curved_edges yes)
				(filter_ratio 0.9)
				(enabled yes)
				(allow_two_segments yes)
				(prefer_zone_connections yes)
			)
		)
		(pad "3" smd roundrect
			(at 0.14 -1.21)
			(size 0.9 0.77)
			(layers "F.Cu" "F.Mask" "F.Paste")
			(roundrect_rratio 0.1)
			(net 51 "Net-(C13-Pad1)")
			(pinfunction "3")
			(pintype "passive")
			(teardrops
				(best_length_ratio 0.2)
				(max_length 1)
				(best_width_ratio 0.9)
				(max_width 2)
				(curved_edges yes)
				(filter_ratio 0.9)
				(enabled yes)
				(allow_two_segments yes)
				(prefer_zone_connections yes)
			)
		)
		(pad "5" smd roundrect
			(at 4.215 1.385)
			(size 0.95 0.5)
			(layers "F.Cu" "F.Mask" "F.Paste")
			(roundrect_rratio 0.1)
			(net 549 "Net-(R14-Pad2)")
			(pinfunction "5")
			(pintype "passive")
			(teardrops
				(best_length_ratio 0.2)
				(max_length 1)
				(best_width_ratio 0.9)
				(max_width 2)
				(curved_edges yes)
				(filter_ratio 0.9)
				(enabled yes)
				(allow_two_segments yes)
				(prefer_zone_connections yes)
			)
		)
		(pad "6" smd roundrect
			(at 4.265 -0.645)
			(size 0.85 0.34)
			(layers "F.Cu" "F.Mask" "F.Paste")
			(roundrect_rratio 0.1)
			(net 295 "/2xUSB3.0+RJ45/GbE.MDI0+")
			(pinfunction "6")
			(pintype "passive")
			(teardrops
				(best_length_ratio 0.2)
				(max_length 1)
				(best_width_ratio 0.9)
				(max_width 2)
				(curved_edges yes)
				(filter_ratio 0.9)
				(enabled yes)
				(allow_two_segments yes)
				(prefer_zone_connections yes)
			)
		)
		(pad "7" smd roundrect
			(at 4.205 -1.43)
			(size 0.97 0.33)
			(layers "F.Cu" "F.Mask" "F.Paste")
			(roundrect_rratio 0.1)
			(net 294 "/2xUSB3.0+RJ45/GbE.MDI0-")
			(pinfunction "7")
			(pintype "passive")
			(teardrops
				(best_length_ratio 0.2)
				(max_length 1)
				(best_width_ratio 0.9)
				(max_width 2)
				(curved_edges yes)
				(filter_ratio 0.9)
				(enabled yes)
				(allow_two_segments yes)
				(prefer_zone_connections yes)
			)
		)
	)
	(footprint "antmicro-footprints:C_0402_1005Metric"
		(layer "F.Cu")
		(at 300.55 102.81 90)
		(descr "Capacitor SMD 0402")
		(tags "capacitor SMD 0402")
		(property "Reference" "C57"
			(at -3 0.45 90)
			(layer "F.SilkS")
			(effects
				(font
					(size 0.7 0.7)
					(thickness 0.15)
				)
				(justify left bottom)
			)
		)
		(property "Value" "C_1u_0402"
			(at -1.022927 2.155213 90)
			(layer "F.Fab")
			(effects
				(font
					(size 0.7 0.7)
					(thickness 0.15)
				)
				(justify left bottom)
			)
		)
		(property "Datasheet" "https://product.tdk.com/en/search/capacitor/ceramic/mlcc/info?part_no=C1005X6S1A105K050BC"
			(at 0 0 90)
			(layer "F.Fab")
			(hide yes)
			(effects
				(font
					(size 1.27 1.27)
					(thickness 0.15)
				)
			)
		)
		(property "Author" "Antmicro"
			(at 403.36 -197.74 0)
			(layer "F.Fab")
			(hide yes)
			(effects
				(font
					(size 1 1)
					(thickness 0.15)
				)
			)
		)
		(property "Dielectric" ""
			(at 403.36 -197.74 0)
			(layer "F.Fab")
			(hide yes)
			(effects
				(font
					(size 1 1)
					(thickness 0.15)
				)
			)
		)
		(property "License" "Apache-2.0"
			(at 403.36 -197.74 0)
			(layer "F.Fab")
			(hide yes)
			(effects
				(font
					(size 1 1)
					(thickness 0.15)
				)
			)
		)
		(property "MPN" "C1005X6S1A105K050BC"
			(at 403.36 -197.74 0)
			(layer "F.Fab")
			(hide yes)
			(effects
				(font
					(size 1 1)
					(thickness 0.15)
				)
			)
		)
		(property "Manufacturer" "TDK"
			(at 403.36 -197.74 0)
			(layer "F.Fab")
			(hide yes)
			(effects
				(font
					(size 1 1)
					(thickness 0.15)
				)
			)
		)
		(property "Public" "False"
			(at 403.36 -197.74 0)
			(layer "F.Fab")
			(hide yes)
			(effects
				(font
					(size 1 1)
					(thickness 0.15)
				)
			)
		)
		(property "Val" "1u"
			(at 403.36 -197.74 0)
			(layer "F.Fab")
			(hide yes)
			(effects
				(font
					(size 1 1)
					(thickness 0.15)
				)
			)
		)
		(property "Voltage" ""
			(at 403.36 -197.74 0)
			(layer "F.Fab")
			(hide yes)
			(effects
				(font
					(size 1 1)
					(thickness 0.15)
				)
			)
		)
		(sheetname "Power")
		(sheetfile "power.kicad_sch")
		(attr smd)
		(fp_rect
			(start -0.925 -0.47)
			(end 0.925 0.47)
			(stroke
				(width 0.05)
				(type default)
			)
			(fill no)
			(layer "F.CrtYd")
		)
		(fp_line
			(start 0.504 -0.25)
			(end 0.504 0.248)
			(stroke
				(width 0.15)
				(type solid)
			)
			(layer "F.Fab")
		)
		(fp_line
			(start -0.494 -0.25)
			(end 0.504 -0.25)
			(stroke
				(width 0.15)
				(type solid)
			)
			(layer "F.Fab")
		)
		(fp_line
			(start 0.504 0.248)
			(end -0.494 0.248)
			(stroke
				(width 0.15)
				(type solid)
			)
			(layer "F.Fab")
		)
		(fp_line
			(start -0.494 0.248)
			(end -0.494 -0.25)
			(stroke
				(width 0.15)
				(type solid)
			)
			(layer "F.Fab")
		)
		(pad "1" smd roundrect
			(at -0.48 0 90)
			(size 0.59 0.64)
			(layers "F.Cu" "F.Mask" "F.Paste")
			(roundrect_rratio 0.25)
			(net 1 "GND")
			(pintype "passive")
			(teardrops
				(best_length_ratio 0.2)
				(max_length 1)
				(best_width_ratio 0.9)
				(max_width 2)
				(curved_edges yes)
				(filter_ratio 0.9)
				(enabled yes)
				(allow_two_segments yes)
				(prefer_zone_connections yes)
			)
		)
		(pad "2" smd roundrect
			(at 0.48 0 90)
			(size 0.59 0.64)
			(layers "F.Cu" "F.Mask" "F.Paste")
			(roundrect_rratio 0.25)
			(net 2 "+3V3")
			(pintype "passive")
			(teardrops
				(best_length_ratio 0.2)
				(max_length 1)
				(best_width_ratio 0.9)
				(max_width 2)
				(curved_edges yes)
				(filter_ratio 0.9)
				(enabled yes)
				(allow_two_segments yes)
				(prefer_zone_connections yes)
			)
		)
	)
	(footprint "antmicro-footprints:TP_SMD_0.75mm"
		(layer "F.Cu")
		(at 144.65 129.56)
		(property "Reference" "TP58"
			(at 0.45 -1.25 90)
			(layer "F.SilkS")
			(effects
				(font
					(size 0.7 0.7)
					(thickness 0.15)
				)
				(justify left bottom)
			)
		)
		(property "Value" "TP_0.75mm_SMD"
			(at 0 1.2 0)
			(layer "F.Fab")
			(effects
				(font
					(size 0.7 0.7)
					(thickness 0.15)
				)
				(justify left bottom)
			)
		)
		(property "Author" "Antmicro"
			(at 0 0 0)
			(layer "F.Fab")
			(hide yes)
			(effects
				(font
					(size 1 1)
					(thickness 0.15)
				)
			)
		)
		(property "License" "Apache-2.0"
			(at 0 0 0)
			(layer "F.Fab")
			(hide yes)
			(effects
				(font
					(size 1 1)
					(thickness 0.15)
				)
			)
		)
		(property "MPN" ""
			(at 0 0 0)
			(layer "F.Fab")
			(hide yes)
			(effects
				(font
					(size 1 1)
					(thickness 0.15)
				)
			)
		)
		(property "Manufacturer" ""
			(at 0 0 0)
			(layer "F.Fab")
			(hide yes)
			(effects
				(font
					(size 1 1)
					(thickness 0.15)
				)
			)
		)
		(property "Public" "False"
			(at 0 0 0)
			(layer "F.Fab")
			(hide yes)
			(effects
				(font
					(size 1 1)
					(thickness 0.15)
				)
			)
		)
		(sheetname "KR to SFI #1")
		(sheetfile "kr_sfi.kicad_sch")
		(attr exclude_from_pos_files exclude_from_bom)
		(fp_circle
			(center 0 0)
			(end 0.475 0)
			(stroke
				(width 0.05)
				(type default)
			)
			(fill no)
			(layer "F.CrtYd")
		)
		(pad "1" smd circle
			(at 0 0)
			(size 0.75 0.75)
			(layers "F.Cu" "F.Mask")
			(net 721 "Net-(U43C-REFCLK1-)")
			(pinfunction "1")
			(pintype "passive")
			(teardrops
				(best_length_ratio 0.4)
				(max_length 1)
				(best_width_ratio 0.9)
				(max_width 2)
				(curved_edges yes)
				(filter_ratio 0.9)
				(enabled yes)
				(allow_two_segments yes)
				(prefer_zone_connections yes)
			)
		)
	)
	(footprint "antmicro-footprints:C_0402_1005Metric"
		(layer "F.Cu")
		(at 193.280022 137.754586 -45)
		(descr "Capacitor SMD 0402")
		(tags "capacitor SMD 0402")
		(property "Reference" "C121"
			(at 3.864615 -0.381761 135)
			(layer "F.SilkS")
			(effects
				(font
					(size 0.7 0.7)
					(thickness 0.15)
				)
				(justify right top)
			)
		)
		(property "Value" "C_100n_0402"
			(at -1.022927 2.155213 135)
			(layer "F.Fab")
			(effects
				(font
					(size 0.7 0.7)
					(thickness 0.15)
				)
				(justify right top)
			)
		)
		(property "Datasheet" "https://www.murata.com/products/productdetail?partno=GRM155R61H104KE14%23"
			(at 0 0 135)
			(layer "B.Fab")
			(hide yes)
			(effects
				(font
					(size 1.27 1.27)
					(thickness 0.15)
				)
				(justify mirror)
			)
		)
		(property "Author" "Antmicro"
			(at 54.168 -327.134 45)
			(layer "F.Fab")
			(hide yes)
			(effects
				(font
					(size 1 1)
					(thickness 0.15)
				)
			)
		)
		(property "Dielectric" "X5R"
			(at 54.168 -327.134 45)
			(layer "F.Fab")
			(hide yes)
			(effects
				(font
					(size 1 1)
					(thickness 0.15)
				)
			)
		)
		(property "License" "Apache-2.0"
			(at 54.168 -327.134 45)
			(layer "F.Fab")
			(hide yes)
			(effects
				(font
					(size 1 1)
					(thickness 0.15)
				)
			)
		)
		(property "MPN" "GRM155R61H104KE14D"
			(at 54.168 -327.134 45)
			(layer "F.Fab")
			(hide yes)
			(effects
				(font
					(size 1 1)
					(thickness 0.15)
				)
			)
		)
		(property "Manufacturer" "Murata"
			(at 54.168 -327.134 45)
			(layer "F.Fab")
			(hide yes)
			(effects
				(font
					(size 1 1)
					(thickness 0.15)
				)
			)
		)
		(property "Public" "False"
			(at 54.168 -327.134 45)
			(layer "F.Fab")
			(hide yes)
			(effects
				(font
					(size 1 1)
					(thickness 0.15)
				)
			)
		)
		(property "Val" "100n"
			(at 54.168 -327.134 45)
			(layer "F.Fab")
			(hide yes)
			(effects
				(font
					(size 1 1)
					(thickness 0.15)
				)
			)
		)
		(property "Voltage" "50V"
			(at 54.168 -327.134 45)
			(layer "F.Fab")
			(hide yes)
			(effects
				(font
					(size 1 1)
					(thickness 0.15)
				)
			)
		)
		(sheetname "PCIe redriver")
		(sheetfile "pcie_redriver.kicad_sch")
		(attr smd)
		(fp_poly
			(pts
				(xy -0.925 -0.47) (xy 0.925 -0.47) (xy 0.925 0.47) (xy -0.925 0.47)
			)
			(stroke
				(width 0.05)
				(type default)
			)
			(fill no)
			(layer "F.CrtYd")
		)
		(fp_line
			(start -0.494 0.248)
			(end -0.494 -0.25)
			(stroke
				(width 0.15)
				(type solid)
			)
			(layer "F.Fab")
		)
		(fp_line
			(start -0.494 -0.25)
			(end 0.504 -0.25)
			(stroke
				(width 0.15)
				(type solid)
			)
			(layer "F.Fab")
		)
		(fp_line
			(start 0.504 0.248)
			(end -0.494 0.248)
			(stroke
				(width 0.15)
				(type solid)
			)
			(layer "F.Fab")
		)
		(fp_line
			(start 0.504 -0.25)
			(end 0.504 0.248)
			(stroke
				(width 0.15)
				(type solid)
			)
			(layer "F.Fab")
		)
		(pad "1" smd roundrect
			(at -0.48 0 315)
			(size 0.59 0.64)
			(layers "F.Cu" "F.Mask" "F.Paste")
			(roundrect_rratio 0.25)
			(net 1 "GND")
			(pintype "passive")
			(teardrops
				(best_length_ratio 0.2)
				(max_length 1)
				(best_width_ratio 0.9)
				(max_width 2)
				(curved_edges yes)
				(filter_ratio 0.9)
				(enabled yes)
				(allow_two_segments yes)
				(prefer_zone_connections yes)
			)
		)
		(pad "2" smd roundrect
			(at 0.48 0 315)
			(size 0.59 0.64)
			(layers "F.Cu" "F.Mask" "F.Paste")
			(roundrect_rratio 0.25)
			(net 2 "+3V3")
			(pintype "passive")
			(teardrops
				(best_length_ratio 0.2)
				(max_length 1)
				(best_width_ratio 0.9)
				(max_width 2)
				(curved_edges yes)
				(filter_ratio 0.9)
				(enabled yes)
				(allow_two_segments yes)
				(prefer_zone_connections yes)
			)
		)
	)
)
